(kicad_pcb
	(version 20260206)
	(generator "pcbnew")
	(generator_version "10.0")
	(general
		(thickness 1.21888)
		(legacy_teardrops no)
	)
	(paper "A4")
	(title_block
		(title "timecard-v8 — TimeCard-DC-V8_EXP.PcbDoc")
		(comment 1 "Time Appliance Project (Time Card) / footprints 73-77 of 288")
	)
	(layers
		(0 "F.Cu" signal "TOP")
		(4 "In1.Cu" signal "SGND")
		(6 "In2.Cu" signal "IN1")
		(8 "In3.Cu" signal "IN2")
		(10 "In4.Cu" signal "SGND1")
		(2 "B.Cu" signal "BOTTOM")
		(9 "F.Adhes" user "F.Adhesive")
		(11 "B.Adhes" user "B.Adhesive")
		(13 "F.Paste" user "Top Paste")
		(15 "B.Paste" user "Bottom Paste")
		(5 "F.SilkS" user "Top Overlay")
		(7 "B.SilkS" user "Bottom Overlay")
		(1 "F.Mask" user "Top Solder")
		(3 "B.Mask" user "Bottom Solder")
		(17 "Dwgs.User" user "User.Drawings")
		(19 "Cmts.User" user "User.Comments")
		(21 "Eco1.User" user "User.Eco1")
		(23 "Eco2.User" user "User.Eco2")
		(25 "Edge.Cuts" user)
		(27 "Margin" user)
		(31 "F.CrtYd" user "Top Courtyard")
		(29 "B.CrtYd" user "Bottom Courtyard")
		(35 "F.Fab" user "Top Component Center")
		(33 "B.Fab" user "Bottom Component Center")
	)
	(footprint "Vault:FP-RUT0012A-MFG"
		(layer "F.Cu")
		(at 219.8761 78.8162)
		(property "Reference" "U21"
			(at 0.078605 -2.173069 0)
			(unlocked yes)
			(layer "F.SilkS")
			(effects
				(font
					(size 0.762 0.762)
					(thickness 0.2286)
				)
			)
		)
		(property "Value" "TMUX1072RUTR"
			(at 7.426665 3.164071 0)
			(unlocked yes)
			(layer "F.SilkS")
			(hide yes)
			(effects
				(font
					(size 0.762 0.762)
					(thickness 0.2286)
				)
			)
		)
		(sheetname "USBUart_DipSelects")
		(sheetfile "USBUart_DipSelects.kicad_sch")
		(duplicate_pad_numbers_are_jumpers no)
		(fp_line
			(start -0.9 -1.525)
			(end 0.9 -1.525)
			(stroke
				(width 0.2)
				(type solid)
			)
			(layer "F.SilkS")
		)
		(fp_line
			(start -0.9 1.525)
			(end 0.9 1.525)
			(stroke
				(width 0.2)
				(type solid)
			)
			(layer "F.SilkS")
		)
		(fp_circle
			(center -1.575 -0.8)
			(end -1.575 -0.925)
			(stroke
				(width 0.25)
				(type solid)
			)
			(fill no)
			(layer "F.SilkS")
		)
		(fp_rect
			(start -0.85 -0.3)
			(end -0.35 -0.5)
			(stroke
				(width 0)
				(type default)
			)
			(fill yes)
			(layer "F.Paste")
		)
		(fp_rect
			(start -0.85 0.1)
			(end -0.35 -0.1)
			(stroke
				(width 0)
				(type default)
			)
			(fill yes)
			(layer "F.Paste")
		)
		(fp_rect
			(start -0.85 0.5)
			(end -0.35 0.3)
			(stroke
				(width 0)
				(type default)
			)
			(fill yes)
			(layer "F.Paste")
		)
		(fp_rect
			(start -0.85 0.9)
			(end -0.35 0.7)
			(stroke
				(width 0)
				(type default)
			)
			(fill yes)
			(layer "F.Paste")
		)
		(fp_rect
			(start -0.1 -0.5)
			(end 0.1 -1)
			(stroke
				(width 0)
				(type default)
			)
			(fill yes)
			(layer "F.Paste")
		)
		(fp_rect
			(start -0.1 1)
			(end 0.1 0.5)
			(stroke
				(width 0)
				(type default)
			)
			(fill yes)
			(layer "F.Paste")
		)
		(fp_rect
			(start 0.35 -0.7)
			(end 0.85 -0.9)
			(stroke
				(width 0)
				(type default)
			)
			(fill yes)
			(layer "F.Paste")
		)
		(fp_rect
			(start 0.35 -0.3)
			(end 0.85 -0.5)
			(stroke
				(width 0)
				(type default)
			)
			(fill yes)
			(layer "F.Paste")
		)
		(fp_rect
			(start 0.35 0.1)
			(end 0.85 -0.1)
			(stroke
				(width 0)
				(type default)
			)
			(fill yes)
			(layer "F.Paste")
		)
		(fp_rect
			(start 0.35 0.5)
			(end 0.85 0.3)
			(stroke
				(width 0)
				(type default)
			)
			(fill yes)
			(layer "F.Paste")
		)
		(fp_rect
			(start 0.35 0.9)
			(end 0.85 0.7)
			(stroke
				(width 0)
				(type default)
			)
			(fill yes)
			(layer "F.Paste")
		)
		(fp_poly
			(pts
				(xy -0.5 -1) (xy -0.35 -1) (xy -0.35 -0.7) (xy -0.85 -0.7) (xy -0.85 -0.9) (xy -0.5 -0.9)
			)
			(stroke
				(width 0)
				(type default)
			)
			(fill yes)
			(layer "F.Paste")
		)
		(fp_line
			(start -1.05 -1.2)
			(end 1.05 -1.2)
			(stroke
				(width 0.2)
				(type solid)
			)
			(layer "F.CrtYd")
		)
		(fp_line
			(start -1.05 1.2)
			(end -1.05 -1.2)
			(stroke
				(width 0.2)
				(type solid)
			)
			(layer "F.CrtYd")
		)
		(fp_line
			(start -1.05 1.2)
			(end 1.05 1.2)
			(stroke
				(width 0.2)
				(type solid)
			)
			(layer "F.CrtYd")
		)
		(fp_line
			(start 1.05 1.2)
			(end 1.05 -1.2)
			(stroke
				(width 0.2)
				(type solid)
			)
			(layer "F.CrtYd")
		)
		(fp_line
			(start -1.05 -1.2)
			(end 1.05 -1.2)
			(stroke
				(width 0.2)
				(type solid)
			)
			(layer "F.Fab")
		)
		(fp_line
			(start -1.05 1.2)
			(end -1.05 -1.2)
			(stroke
				(width 0.2)
				(type solid)
			)
			(layer "F.Fab")
		)
		(fp_line
			(start -1.05 1.2)
			(end 1.05 1.2)
			(stroke
				(width 0.2)
				(type solid)
			)
			(layer "F.Fab")
		)
		(fp_line
			(start -0.5 0)
			(end 0.5 0)
			(stroke
				(width 0.1)
				(type solid)
			)
			(layer "F.Fab")
		)
		(fp_line
			(start 0 0.5)
			(end 0 -0.5)
			(stroke
				(width 0.1)
				(type solid)
			)
			(layer "F.Fab")
		)
		(fp_line
			(start 1.05 1.2)
			(end 1.05 -1.2)
			(stroke
				(width 0.2)
				(type solid)
			)
			(layer "F.Fab")
		)
		(fp_text user "${REFERENCE}"
			(at -0.00001 0.09602 0)
			(unlocked yes)
			(layer "F.Fab")
			(effects
				(font
					(face "Arial")
					(size 0.63 0.63)
					(thickness 0.1)
				)
				(justify left bottom)
			)
		)
		(pad "" smd custom
			(at -0.5 -1.1)
			(size 0.000001 0.000001)
			(layers "F.Cu" "F.Mask")
			(solder_mask_margin 0)
			(thermal_bridge_angle 90)
			(options
				(clearance outline)
				(anchor circle)
			)
			(primitives
				(gr_poly
					(pts
						(xy 0 0) (xy 0.15 0) (xy 0.15 0.4) (xy -0.45 0.4) (xy -0.45 0.2) (xy 0 0.2)
					)
					(width 0)
					(fill yes)
				)
			)
		)
		(pad "1" smd circle
			(at -0.45 -0.8)
			(size 0.18 0.18)
			(layers "F.Cu" "F.Mask" "F.Paste")
			(net "DIP_SW_UART_SEL")
			(solder_mask_margin 0)
			(solder_paste_margin -1000)
			(thermal_bridge_angle 90)
		)
		(pad "2" smd rect
			(at -0.65 -0.4)
			(size 0.6 0.2)
			(layers "F.Cu" "F.Mask" "F.Paste")
			(net "NetR85_2")
			(solder_mask_margin 0)
			(solder_paste_margin -1000)
		)
		(pad "3" smd rect
			(at -0.65 0)
			(size 0.6 0.2)
			(layers "F.Cu" "F.Mask" "F.Paste")
			(net "GND")
			(solder_mask_margin 0)
			(solder_paste_margin -1000)
		)
		(pad "4" smd rect
			(at -0.65 0.4)
			(size 0.6 0.2)
			(layers "F.Cu" "F.Mask" "F.Paste")
			(net "NetR87_2")
			(solder_mask_margin 0)
			(solder_paste_margin -1000)
		)
		(pad "5" smd rect
			(at -0.65 0.8)
			(size 0.6 0.2)
			(layers "F.Cu" "F.Mask" "F.Paste")
			(net "DIP_SW_UART_SEL")
			(solder_mask_margin 0)
			(solder_paste_margin -1000)
		)
		(pad "6" smd rect
			(at 0 0.8)
			(size 0.2 0.6)
			(layers "F.Cu" "F.Mask" "F.Paste")
			(net "GND")
			(solder_mask_margin 0)
			(solder_paste_margin -1000)
		)
		(pad "7" smd rect
			(at 0.65 0.8)
			(size 0.6 0.2)
			(layers "F.Cu" "F.Mask" "F.Paste")
			(net "UART1_RXD")
			(solder_mask_margin 0)
			(solder_paste_margin -1000)
		)
		(pad "8" smd rect
			(at 0.65 0.4)
			(size 0.6 0.2)
			(layers "F.Cu" "F.Mask" "F.Paste")
			(net "NetR86_2")
			(solder_mask_margin 0)
			(solder_paste_margin -1000)
		)
		(pad "9" smd rect
			(at 0.65 0)
			(size 0.6 0.2)
			(layers "F.Cu" "F.Mask" "F.Paste")
			(net "+3.3V")
			(solder_mask_margin 0)
			(solder_paste_margin -1000)
		)
		(pad "10" smd rect
			(at 0.65 -0.4)
			(size 0.6 0.2)
			(layers "F.Cu" "F.Mask" "F.Paste")
			(net "NetR84_2")
			(solder_mask_margin 0)
			(solder_paste_margin -1000)
		)
		(pad "11" smd rect
			(at 0.65 -0.8)
			(size 0.6 0.2)
			(layers "F.Cu" "F.Mask" "F.Paste")
			(net "UART1_TXD")
			(solder_mask_margin 0)
			(solder_paste_margin -1000)
		)
		(pad "12" smd rect
			(at 0 -0.8)
			(size 0.2 0.6)
			(layers "F.Cu" "F.Mask" "F.Paste")
			(net "GND")
			(solder_mask_margin 0)
			(solder_paste_margin -1000)
		)
	)
	(footprint "Vault:FP-ERJ2R-MFG"
		(layer "F.Cu")
		(at 237.3261 62.1162 -90)
		(property "Reference" "R83"
			(at -2.0714 -0.273069 270)
			(unlocked yes)
			(layer "F.SilkS")
			(effects
				(font
					(size 0.762 0.762)
					(thickness 0.2286)
				)
			)
		)
		(property "Value" "15K_1%_0402"
			(at -2.732271 8.011115 180)
			(unlocked yes)
			(layer "F.SilkS")
			(hide yes)
			(effects
				(font
					(size 0.762 0.762)
					(thickness 0.2286)
				)
			)
		)
		(sheetname "USBUart_DipSelects")
		(sheetfile "USBUart_DipSelects.kicad_sch")
		(duplicate_pad_numbers_are_jumpers no)
		(fp_line
			(start 0.521 0.636)
			(end -0.529 0.636)
			(stroke
				(width 0.2)
				(type solid)
			)
			(layer "F.SilkS")
		)
		(fp_line
			(start 0.525 -0.65)
			(end -0.525 -0.65)
			(stroke
				(width 0.2)
				(type solid)
			)
			(layer "F.SilkS")
		)
		(fp_line
			(start -0.85 0.375)
			(end -0.85 -0.375)
			(stroke
				(width 0.2)
				(type solid)
			)
			(layer "F.CrtYd")
		)
		(fp_line
			(start 0.85 0.375)
			(end -0.85 0.375)
			(stroke
				(width 0.2)
				(type solid)
			)
			(layer "F.CrtYd")
		)
		(fp_line
			(start 0.85 0.375)
			(end 0.85 -0.375)
			(stroke
				(width 0.2)
				(type solid)
			)
			(layer "F.CrtYd")
		)
		(fp_line
			(start 0.85 -0.375)
			(end -0.85 -0.375)
			(stroke
				(width 0.2)
				(type solid)
			)
			(layer "F.CrtYd")
		)
		(fp_line
			(start 0 0.5)
			(end 0 -0.5)
			(stroke
				(width 0.1)
				(type solid)
			)
			(layer "F.Fab")
		)
		(fp_line
			(start -0.85 0.375)
			(end -0.85 -0.375)
			(stroke
				(width 0.2)
				(type solid)
			)
			(layer "F.Fab")
		)
		(fp_line
			(start 0.85 0.375)
			(end -0.85 0.375)
			(stroke
				(width 0.2)
				(type solid)
			)
			(layer "F.Fab")
		)
		(fp_line
			(start 0.85 0.375)
			(end 0.85 -0.375)
			(stroke
				(width 0.2)
				(type solid)
			)
			(layer "F.Fab")
		)
		(fp_line
			(start 0.5 0)
			(end -0.5 0)
			(stroke
				(width 0.1)
				(type solid)
			)
			(layer "F.Fab")
		)
		(fp_line
			(start 0.85 -0.375)
			(end -0.85 -0.375)
			(stroke
				(width 0.2)
				(type solid)
			)
			(layer "F.Fab")
		)
		(fp_text user "${REFERENCE}"
			(at -0.00001 0.09602 270)
			(unlocked yes)
			(layer "F.Fab")
			(effects
				(font
					(face "Arial")
					(size 0.63 0.63)
					(thickness 0.1)
				)
				(justify left bottom)
			)
		)
		(pad "1" smd rect
			(at -0.5125 0 270)
			(size 0.475 0.5)
			(layers "F.Cu" "F.Mask" "F.Paste")
			(net "GND")
			(solder_mask_margin 0)
			(solder_paste_margin 0)
		)
		(pad "2" smd rect
			(at 0.5125 0 270)
			(size 0.475 0.5)
			(layers "F.Cu" "F.Mask" "F.Paste")
			(net "NetC91_1")
			(solder_mask_margin 0)
			(solder_paste_margin 0)
		)
	)
	(footprint "Vault:RESC1608X55X25NL10T15"
		(layer "F.Cu")
		(at 77.8761 121.8662 180)
		(property "Reference" "R28"
			(at 0.81672 1.068825 0)
			(unlocked yes)
			(layer "F.SilkS")
			(effects
				(font
					(size 0.762 0.762)
					(thickness 0.2286)
				)
				(justify left bottom)
			)
		)
		(property "Value" "49.9R"
			(at 1.1445 -4.336645 0)
			(unlocked yes)
			(layer "F.SilkS")
			(hide yes)
			(effects
				(font
					(size 0.762 0.762)
					(thickness 0.2286)
				)
				(justify left bottom)
			)
		)
		(sheetname "USER_IO")
		(sheetfile "USER_IO.kicad_sch")
		(duplicate_pad_numbers_are_jumpers no)
		(pad "1" smd rect
			(at -0.7 0 270)
			(size 0.9 0.7)
			(layers "F.Cu" "F.Mask" "F.Paste")
			(net "NetR28_1")
		)
		(pad "2" smd rect
			(at 0.7 0 270)
			(size 0.9 0.7)
			(layers "F.Cu" "F.Mask" "F.Paste")
			(net "NetAN3_1")
		)
	)
	(footprint "Vault:FP-RUT0012A-MFG"
		(layer "F.Cu")
		(at 211.5261 78.8162)
		(property "Reference" "U22"
			(at 0.1286 -2.273069 0)
			(unlocked yes)
			(layer "F.SilkS")
			(effects
				(font
					(size 0.762 0.762)
					(thickness 0.2286)
				)
			)
		)
		(property "Value" "TMUX1072RUTR"
			(at 7.426665 3.164071 0)
			(unlocked yes)
			(layer "F.SilkS")
			(hide yes)
			(effects
				(font
					(size 0.762 0.762)
					(thickness 0.2286)
				)
			)
		)
		(sheetname "USBUart_DipSelects")
		(sheetfile "USBUart_DipSelects.kicad_sch")
		(duplicate_pad_numbers_are_jumpers no)
		(fp_line
			(start -0.9 -1.525)
			(end 0.9 -1.525)
			(stroke
				(width 0.2)
				(type solid)
			)
			(layer "F.SilkS")
		)
		(fp_line
			(start -0.9 1.525)
			(end 0.9 1.525)
			(stroke
				(width 0.2)
				(type solid)
			)
			(layer "F.SilkS")
		)
		(fp_circle
			(center -1.575 -0.8)
			(end -1.575 -0.925)
			(stroke
				(width 0.25)
				(type solid)
			)
			(fill no)
			(layer "F.SilkS")
		)
		(fp_rect
			(start -0.85 -0.3)
			(end -0.35 -0.5)
			(stroke
				(width 0)
				(type default)
			)
			(fill yes)
			(layer "F.Paste")
		)
		(fp_rect
			(start -0.85 0.1)
			(end -0.35 -0.1)
			(stroke
				(width 0)
				(type default)
			)
			(fill yes)
			(layer "F.Paste")
		)
		(fp_rect
			(start -0.85 0.5)
			(end -0.35 0.3)
			(stroke
				(width 0)
				(type default)
			)
			(fill yes)
			(layer "F.Paste")
		)
		(fp_rect
			(start -0.85 0.9)
			(end -0.35 0.7)
			(stroke
				(width 0)
				(type default)
			)
			(fill yes)
			(layer "F.Paste")
		)
		(fp_rect
			(start -0.1 -0.5)
			(end 0.1 -1)
			(stroke
				(width 0)
				(type default)
			)
			(fill yes)
			(layer "F.Paste")
		)
		(fp_rect
			(start -0.1 1)
			(end 0.1 0.5)
			(stroke
				(width 0)
				(type default)
			)
			(fill yes)
			(layer "F.Paste")
		)
		(fp_rect
			(start 0.35 -0.7)
			(end 0.85 -0.9)
			(stroke
				(width 0)
				(type default)
			)
			(fill yes)
			(layer "F.Paste")
		)
		(fp_rect
			(start 0.35 -0.3)
			(end 0.85 -0.5)
			(stroke
				(width 0)
				(type default)
			)
			(fill yes)
			(layer "F.Paste")
		)
		(fp_rect
			(start 0.35 0.1)
			(end 0.85 -0.1)
			(stroke
				(width 0)
				(type default)
			)
			(fill yes)
			(layer "F.Paste")
		)
		(fp_rect
			(start 0.35 0.5)
			(end 0.85 0.3)
			(stroke
				(width 0)
				(type default)
			)
			(fill yes)
			(layer "F.Paste")
		)
		(fp_rect
			(start 0.35 0.9)
			(end 0.85 0.7)
			(stroke
				(width 0)
				(type default)
			)
			(fill yes)
			(layer "F.Paste")
		)
		(fp_poly
			(pts
				(xy -0.5 -1) (xy -0.35 -1) (xy -0.35 -0.7) (xy -0.85 -0.7) (xy -0.85 -0.9) (xy -0.5 -0.9)
			)
			(stroke
				(width 0)
				(type default)
			)
			(fill yes)
			(layer "F.Paste")
		)
		(fp_line
			(start -1.05 -1.2)
			(end 1.05 -1.2)
			(stroke
				(width 0.2)
				(type solid)
			)
			(layer "F.CrtYd")
		)
		(fp_line
			(start -1.05 1.2)
			(end -1.05 -1.2)
			(stroke
				(width 0.2)
				(type solid)
			)
			(layer "F.CrtYd")
		)
		(fp_line
			(start -1.05 1.2)
			(end 1.05 1.2)
			(stroke
				(width 0.2)
				(type solid)
			)
			(layer "F.CrtYd")
		)
		(fp_line
			(start 1.05 1.2)
			(end 1.05 -1.2)
			(stroke
				(width 0.2)
				(type solid)
			)
			(layer "F.CrtYd")
		)
		(fp_line
			(start -1.05 -1.2)
			(end 1.05 -1.2)
			(stroke
				(width 0.2)
				(type solid)
			)
			(layer "F.Fab")
		)
		(fp_line
			(start -1.05 1.2)
			(end -1.05 -1.2)
			(stroke
				(width 0.2)
				(type solid)
			)
			(layer "F.Fab")
		)
		(fp_line
			(start -1.05 1.2)
			(end 1.05 1.2)
			(stroke
				(width 0.2)
				(type solid)
			)
			(layer "F.Fab")
		)
		(fp_line
			(start -0.5 0)
			(end 0.5 0)
			(stroke
				(width 0.1)
				(type solid)
			)
			(layer "F.Fab")
		)
		(fp_line
			(start 0 0.5)
			(end 0 -0.5)
			(stroke
				(width 0.1)
				(type solid)
			)
			(layer "F.Fab")
		)
		(fp_line
			(start 1.05 1.2)
			(end 1.05 -1.2)
			(stroke
				(width 0.2)
				(type solid)
			)
			(layer "F.Fab")
		)
		(fp_text user "${REFERENCE}"
			(at -0.00001 0.09602 0)
			(unlocked yes)
			(layer "F.Fab")
			(effects
				(font
					(face "Arial")
					(size 0.63 0.63)
					(thickness 0.1)
				)
				(justify left bottom)
			)
		)
		(pad "" smd custom
			(at -0.5 -1.1)
			(size 0.000001 0.000001)
			(layers "F.Cu" "F.Mask")
			(solder_mask_margin 0)
			(thermal_bridge_angle 90)
			(options
				(clearance outline)
				(anchor circle)
			)
			(primitives
				(gr_poly
					(pts
						(xy 0 0) (xy 0.15 0) (xy 0.15 0.4) (xy -0.45 0.4) (xy -0.45 0.2) (xy 0 0.2)
					)
					(width 0)
					(fill yes)
				)
			)
		)
		(pad "1" smd circle
			(at -0.45 -0.8)
			(size 0.18 0.18)
			(layers "F.Cu" "F.Mask" "F.Paste")
			(net "DIP_SW_UART_SEL")
			(solder_mask_margin 0)
			(solder_paste_margin -1000)
			(thermal_bridge_angle 90)
		)
		(pad "2" smd rect
			(at -0.65 -0.4)
			(size 0.6 0.2)
			(layers "F.Cu" "F.Mask" "F.Paste")
			(net "NetR91_2")
			(solder_mask_margin 0)
			(solder_paste_margin -1000)
		)
		(pad "3" smd rect
			(at -0.65 0)
			(size 0.6 0.2)
			(layers "F.Cu" "F.Mask" "F.Paste")
			(net "GND")
			(solder_mask_margin 0)
			(solder_paste_margin -1000)
		)
		(pad "4" smd rect
			(at -0.65 0.4)
			(size 0.6 0.2)
			(layers "F.Cu" "F.Mask" "F.Paste")
			(net "NetR93_2")
			(solder_mask_margin 0)
			(solder_paste_margin -1000)
		)
		(pad "5" smd rect
			(at -0.65 0.8)
			(size 0.6 0.2)
			(layers "F.Cu" "F.Mask" "F.Paste")
			(net "DIP_SW_UART_SEL")
			(solder_mask_margin 0)
			(solder_paste_margin -1000)
		)
		(pad "6" smd rect
			(at 0 0.8)
			(size 0.2 0.6)
			(layers "F.Cu" "F.Mask" "F.Paste")
			(net "GND")
			(solder_mask_margin 0)
			(solder_paste_margin -1000)
		)
		(pad "7" smd rect
			(at 0.65 0.8)
			(size 0.6 0.2)
			(layers "F.Cu" "F.Mask" "F.Paste")
			(net "GPS2_RX")
			(solder_mask_margin 0)
			(solder_paste_margin -1000)
		)
		(pad "8" smd rect
			(at 0.65 0.4)
			(size 0.6 0.2)
			(layers "F.Cu" "F.Mask" "F.Paste")
			(net "NetR92_2")
			(solder_mask_margin 0)
			(solder_paste_margin -1000)
		)
		(pad "9" smd rect
			(at 0.65 0)
			(size 0.6 0.2)
			(layers "F.Cu" "F.Mask" "F.Paste")
			(net "+3.3V")
			(solder_mask_margin 0)
			(solder_paste_margin -1000)
		)
		(pad "10" smd rect
			(at 0.65 -0.4)
			(size 0.6 0.2)
			(layers "F.Cu" "F.Mask" "F.Paste")
			(net "NetR90_2")
			(solder_mask_margin 0)
			(solder_paste_margin -1000)
		)
		(pad "11" smd rect
			(at 0.65 -0.8)
			(size 0.6 0.2)
			(layers "F.Cu" "F.Mask" "F.Paste")
			(net "GPS2_TX")
			(solder_mask_margin 0)
			(solder_paste_margin -1000)
		)
		(pad "12" smd rect
			(at 0 -0.8)
			(size 0.2 0.6)
			(layers "F.Cu" "F.Mask" "F.Paste")
			(net "GND")
			(solder_mask_margin 0)
			(solder_paste_margin -1000)
		)
	)
	(footprint "SA53:SolderSocket"
		(layer "F.Cu")
		(at 134.8261 138.2162 90)
		(property "Reference" "SKT3"
			(at -3.426921 2.1286 0)
			(unlocked yes)
			(layer "F.SilkS")
			(effects
				(font
					(size 0.762 0.762)
					(thickness 0.2286)
				)
			)
		)
		(property "Value" "0332-0-43-80-18-27-10-0"
			(at -2.910071 16.1362 0)
			(unlocked yes)
			(layer "F.SilkS")
			(hide yes)
			(effects
				(font
					(size 0.762 0.762)
					(thickness 0.2286)
				)
			)
		)
		(sheetname "MAC")
		(sheetfile "MAC.kicad_sch")
		(duplicate_pad_numbers_are_jumpers no)
		(pad "1" thru_hole circle
			(at 0 0 90)
			(size 2.54 2.54)
			(drill 2.0066)
			(layers "*.Cu" "*.Mask")
			(remove_unused_layers no)
			(net "MAC_RX")
			(thermal_bridge_angle 90)
		)
	)
)
